# S9S_MB_2U (Grand Teton) — schematic netlist excerpt (pin names and nets, part order shuffled) for the footprints in the layout excerpt that follows; sources: Cadence DE-HDL packaged netlist, KiCad conversion of 03242023_DA0F0TMBIJ0_F0T_Motherboard_J_brd_V01_OCP.brd

R4262  Q_RES  240 1% EMPTY  pkg 0402LF  page 119 : A = PVNN_TERM_CPU0 ; B = PD_CPU0_BIST_ENABLE
PC1277  Q_CAP  22UF 4V 20% X6S  pkg C0805  page 282 : A = PVNN_MAIN_CPU0 ; B = GND
C847  Q_CAP_DIFFBUS  DIFF BUS_0.22UF 6.3V 20% X6S  pkg C0201  page 174 : \1\ = P5E_CPU0_PE1_TX_C_DP<11> ; \2\ = P5E_CPU0_PE1_TX_DP<11>

(kicad_pcb
	(version 20260206)
	(generator "pcbnew")
	(generator_version "10.0")
	(general
		(thickness 1.6)
		(legacy_teardrops no)
	)
	(paper "A4")
	(title_block
		(title "03242023_DA0F0TMBIJ0_F0T_Motherboard_J_brd_V01_OCP.brd")
		(comment 1 "Grand Teton / footprints 3234-3236 of 6105")
	)
	(layers
		(0 "F.Cu" signal "TOP")
		(4 "In1.Cu" signal "GND")
		(6 "In2.Cu" signal "IN1")
		(8 "In3.Cu" signal "GND1")
		(10 "In4.Cu" signal "IN2")
		(12 "In5.Cu" signal "GND2")
		(14 "In6.Cu" signal "IN3")
		(16 "In7.Cu" signal "GND3")
		(18 "In8.Cu" signal "VCC")
		(20 "In9.Cu" signal "VCC1")
		(22 "In10.Cu" signal "GND4")
		(24 "In11.Cu" signal "IN4")
		(26 "In12.Cu" signal "GND5")
		(28 "In13.Cu" signal "IN5")
		(30 "In14.Cu" signal "GND6")
		(32 "In15.Cu" signal "IN6")
		(34 "In16.Cu" signal "GND7")
		(2 "B.Cu" signal "BOTTOM")
		(9 "F.Adhes" user "F.Adhesive")
		(11 "B.Adhes" user "B.Adhesive")
		(13 "F.Paste" user "Package Geometry/Pastemask Top")
		(15 "B.Paste" user "Package Geometry/Pastemask Bottom")
		(5 "F.SilkS" user "Ref Des/Silkscreen Top")
		(7 "B.SilkS" user "Ref Des/Silkscreen Bottom")
		(1 "F.Mask" user "Board Geometry/Soldermask Top")
		(3 "B.Mask" user "Board Geometry/Soldermask Bottom")
		(17 "Dwgs.User" user "User.Drawings")
		(19 "Cmts.User" user "User.Comments")
		(21 "Eco1.User" user "User.Eco1")
		(23 "Eco2.User" user "User.Eco2")
		(25 "Edge.Cuts" user "Board Geometry/Outline")
		(27 "Margin" user)
		(31 "F.CrtYd" user "Package Geometry/Place Bound Top")
		(29 "B.CrtYd" user "Package Geometry/Place Bound Bottom")
		(35 "F.Fab" user "Ref Des/Assembly Top")
		(33 "B.Fab" user "Ref Des/Assembly Bottom")
	)
	(footprint ""
		(layer "F.Cu")
		(at 327.770998 -190.74511 90)
		(property "Reference" "R4262"
			(at 0 0 90)
			(layer "F.SilkS")
			(hide yes)
			(effects
				(font
					(size 1.27 1.27)
				)
			)
		)
		(property "Value" ""
			(at 0 0 90)
			(layer "F.Fab")
			(effects
				(font
					(size 1.27 1.27)
				)
			)
		)
		(duplicate_pad_numbers_are_jumpers no)
		(fp_line
			(start 0.7874 -0.4064)
			(end 0.7874 0.4064)
			(stroke
				(width 0.1524)
				(type default)
			)
			(layer "F.SilkS")
		)
		(fp_line
			(start -0.7874 -0.4064)
			(end 0.7874 -0.4064)
			(stroke
				(width 0.1524)
				(type default)
			)
			(layer "F.SilkS")
		)
		(fp_line
			(start 0.7874 0.4064)
			(end -0.7874 0.4064)
			(stroke
				(width 0.1524)
				(type default)
			)
			(layer "F.SilkS")
		)
		(fp_line
			(start -0.7874 0.4064)
			(end -0.7874 -0.4064)
			(stroke
				(width 0.1524)
				(type default)
			)
			(layer "F.SilkS")
		)
		(fp_line
			(start -0.12065 -0.305054)
			(end -0.12065 -0.2794)
			(stroke
				(width 0.1)
				(type default)
			)
			(layer "F.Fab")
		)
		(fp_line
			(start -0.67945 -0.305054)
			(end -0.12065 -0.305054)
			(stroke
				(width 0.1)
				(type default)
			)
			(layer "F.Fab")
		)
		(fp_line
			(start 0.67945 -0.3048)
			(end 0.67945 0.3048)
			(stroke
				(width 0.1)
				(type default)
			)
			(layer "F.Fab")
		)
		(fp_line
			(start 0.12065 -0.3048)
			(end 0.67945 -0.3048)
			(stroke
				(width 0.1)
				(type default)
			)
			(layer "F.Fab")
		)
		(fp_line
			(start 0.12065 -0.2794)
			(end 0.12065 -0.3048)
			(stroke
				(width 0.1)
				(type default)
			)
			(layer "F.Fab")
		)
		(fp_line
			(start -0.12065 -0.2794)
			(end 0.12065 -0.2794)
			(stroke
				(width 0.1)
				(type default)
			)
			(layer "F.Fab")
		)
		(fp_line
			(start 0.120396 0.2794)
			(end -0.12065 0.2794)
			(stroke
				(width 0.1)
				(type default)
			)
			(layer "F.Fab")
		)
		(fp_line
			(start -0.12065 0.2794)
			(end -0.12065 0.3048)
			(stroke
				(width 0.1)
				(type default)
			)
			(layer "F.Fab")
		)
		(fp_line
			(start 0.67945 0.3048)
			(end 0.120396 0.3048)
			(stroke
				(width 0.1)
				(type default)
			)
			(layer "F.Fab")
		)
		(fp_line
			(start 0.120396 0.3048)
			(end 0.120396 0.2794)
			(stroke
				(width 0.1)
				(type default)
			)
			(layer "F.Fab")
		)
		(fp_line
			(start -0.12065 0.3048)
			(end -0.67945 0.3048)
			(stroke
				(width 0.1)
				(type default)
			)
			(layer "F.Fab")
		)
		(fp_line
			(start -0.67945 0.3048)
			(end -0.67945 -0.305054)
			(stroke
				(width 0.1)
				(type default)
			)
			(layer "F.Fab")
		)
		(pad "1" smd circle
			(at -0.40005 0 90)
			(size 0 0)
			(layers "F.Cu" "F.Mask" "F.Paste")
			(net "PVNN_TERM_CPU0")
		)
		(pad "2" smd circle
			(at 0.40005 0 90)
			(size 0 0)
			(layers "F.Cu" "F.Mask" "F.Paste")
			(net "PD_CPU0_BIST_ENABLE")
		)
	)
	(footprint ""
		(layer "F.Cu")
		(at 446.740026 -184.028842)
		(property "Reference" "PC1277"
			(at 0 0 0)
			(layer "F.SilkS")
			(hide yes)
			(effects
				(font
					(size 1.27 1.27)
				)
			)
		)
		(property "Value" ""
			(at 0 0 0)
			(layer "F.Fab")
			(effects
				(font
					(size 1.27 1.27)
				)
			)
		)
		(duplicate_pad_numbers_are_jumpers no)
		(fp_line
			(start -1.524 -0.762)
			(end 1.524 -0.762)
			(stroke
				(width 0.1524)
				(type default)
			)
			(layer "F.SilkS")
		)
		(fp_line
			(start -1.524 0.762)
			(end -1.524 -0.762)
			(stroke
				(width 0.1524)
				(type default)
			)
			(layer "F.SilkS")
		)
		(fp_line
			(start 1.524 -0.762)
			(end 1.524 0.762)
			(stroke
				(width 0.1524)
				(type default)
			)
			(layer "F.SilkS")
		)
		(fp_line
			(start 1.524 0.762)
			(end -1.524 0.762)
			(stroke
				(width 0.1524)
				(type default)
			)
			(layer "F.SilkS")
		)
		(fp_line
			(start -1.1049 -0.724916)
			(end -1.1049 0.724916)
			(stroke
				(width 0.1)
				(type default)
			)
			(layer "F.Fab")
		)
		(fp_line
			(start -1.1049 0.724916)
			(end 1.1049 0.724916)
			(stroke
				(width 0.1)
				(type default)
			)
			(layer "F.Fab")
		)
		(fp_line
			(start 1.1049 -0.724916)
			(end -1.1049 -0.724916)
			(stroke
				(width 0.1)
				(type default)
			)
			(layer "F.Fab")
		)
		(fp_line
			(start 1.1049 0.724916)
			(end 1.1049 -0.724916)
			(stroke
				(width 0.1)
				(type default)
			)
			(layer "F.Fab")
		)
		(pad "1" smd rect
			(at -0.889 0 180)
			(size 1.016 1.27)
			(layers "F.Cu" "F.Mask" "F.Paste")
			(net "PVNN_MAIN_CPU0")
		)
		(pad "2" smd rect
			(at 0.889 0 180)
			(size 1.016 1.27)
			(layers "F.Cu" "F.Mask" "F.Paste")
			(net "GND")
		)
	)
	(footprint ""
		(layer "F.Cu")
		(at 401.191984 -16.088614 90)
		(property "Reference" "C847"
			(at 0 0 90)
			(layer "F.SilkS")
			(hide yes)
			(effects
				(font
					(size 1.27 1.27)
				)
			)
		)
		(property "Value" ""
			(at 0 0 90)
			(layer "F.Fab")
			(effects
				(font
					(size 1.27 1.27)
				)
			)
		)
		(duplicate_pad_numbers_are_jumpers no)
		(fp_line
			(start 0.299974 -0.150114)
			(end 0.299974 0.150114)
			(stroke
				(width 0.1)
				(type default)
			)
			(layer "F.Fab")
		)
		(fp_line
			(start -0.299974 -0.150114)
			(end 0.299974 -0.150114)
			(stroke
				(width 0.1)
				(type default)
			)
			(layer "F.Fab")
		)
		(fp_line
			(start 0.299974 0.150114)
			(end -0.299974 0.150114)
			(stroke
				(width 0.1)
				(type default)
			)
			(layer "F.Fab")
		)
		(fp_line
			(start -0.299974 0.150114)
			(end -0.299974 -0.150114)
			(stroke
				(width 0.1)
				(type default)
			)
			(layer "F.Fab")
		)
		(pad "1" smd rect
			(at -0.2667 0 90)
			(size 0.3048 0.381)
			(layers "F.Cu" "F.Mask" "F.Paste")
			(net "P5E_CPU0_PE1_TX_C_DP<11>")
		)
		(pad "2" smd rect
			(at 0.2667 0 90)
			(size 0.3048 0.381)
			(layers "F.Cu" "F.Mask" "F.Paste")
			(net "P5E_CPU0_PE1_TX_DP<11>")
		)
	)
)
